FILE_TYPE = CONNECTIVITY;
{Allegro Design Entry HDL 17.4-2019 S026 (4007227) 1/17/2022}
"PAGE_NUMBER" = 197;
0"NC";
1"GND\g";
2"GND\g";
3"GND\g";
4"GND\g";
5"GND\g";
6"GND\g";
7"GND\g";
8"GND\g";
9"GND\g";
10"GND\g";
11"GND\g";
12"P12V_AUX\g";
13"SW_PVDDIO_P1_BOOT2";
14"SW_P12V_AUX_PVDDIO_P1_FLT\g";
15"PVDDCR_CPU1_P1_VCCS"CDS_PHYS_NET_NAME"PVDDCR_CPU1_P1_VCCS";
16"SW_P12V_AUX_PVDDIO_P1_FLT\g";
17"GND\g";
18"PVDDIO_P1_VOS1";
19"SW_PVDDIO_P1_SW1";
20"SW_PVDDIO_P1_BOOTR1";
21"SW_PVDDIO_P1_BOOT1";
22"PVDDCR_CPU1_P1_PVCC\g";
23"GND\g";
24"GND\g";
25"PVDDCR_CPU1_P1_PVCC\g";
26"GND\g";
27"PVDDIO_P1\g";
28"GND\g";
29"PVDDIO_P1\g";
30"GND\g";
31"GND\g";
32"PVDDIO_P1\g";
33"SW_PVDDIO_P1_BOOT1_R";
34"SW_PVDDIO_P1_BOOT2_R";
35"SW_PVDDIO_P1_SW2";
36"SW_PVDDIO_P1_BOOTR2";
37"PVDDIO_P1_TEMP1";
38"PVDDIO_P1_PWM2";
39"PVDDIO_P1_VCC2"CDS_PHYS_NET_NAME"PVDDIO_P1_VCC2";
40"SW_PVDDIO_P1_SW1_RC";
41"NC_PVDDIO_P1_GL1_1";
42"PVDDIO_P1_LSET1"CDS_PHYS_NET_NAME"PVDDIO_P1_LSET1";
43"PVDDIO_P1_VCC1"CDS_PHYS_NET_NAME"PVDDIO_P1_VCC1";
44"PVDDIO_P1_TEMP1";
45"PVDDIO_P1_IMON1";
46"IND_PVDDIO_P1_CPL2";
47"IND_PVDDIO_P1_CPL2";
48"IND_PVDDIO_P1_CPL3";
49"NC_PVDDIO_P1_GL2_1";
50"PVDDIO_P1_PWM1";
51"NC_PVDDIO_P1_DNC1";
52"SW_PVDDIO_P1_SW2_RC";
53"PVDDIO_P1_VOS2";
54"NC_PVDDIO_P1_GL1_2";
55"NC_PVDDIO_P1_GL2_2";
56"PVDDIO_P1_IMON2";
57"NC_PVDDIO_P1_DNC2";
58"PVDDCR_CPU1_P1_VCCS"CDS_PHYS_NET_NAME"PVDDCR_CPU1_P1_VCCS";
59"PVDDIO_P1_LSET2";
60"GND\g";
%"UNIVERSAL_GND"
"1","(100,1675)","0","pure_quanta_power","I1";
;
CDS_LIB"pure_quanta_power"
HDL_POWER"GND";
"A"1;
%"UNIVERSAL_GND"
"1","(975,2450)","0","pure_quanta_power","I11";
;
CDS_LIB"pure_quanta_power"
HDL_POWER"GND";
"A"2;
%"Q_CAP"
"1","(975,2650)","0","pure_quanta","I12";
;
LOCATION"PC432"
$SEC"1"
CDS_SEC"1"
TOLERANCE"10%"
VALUE"2.2UF"
VOLTAGE"10V"
PACK_TYPE"C0402"
MATERIAL"X6S"
CDS_LIB"pure_quanta"
PART_NUMBER"CH5222KEB01";
"B"
$PN"2"2;
"A"
$PN"1"39;
%"Q_RES"
"2","(975,3200)","0","pure_quanta","I13";
;
LOCATION"PR276"
$SEC"1"
CDS_SEC"1"
WATTAGE"1/16W"
MATERIAL"CHIP"
TOLERANCE"1%"
VALUE"2.2"
PACK_TYPE"0402LF"
CDS_LIB"pure_quanta"
PART_NUMBER"CS-2202FB01";
"A"
$PN"1"22;
"B"
$PN"2"39;
%"VCC_CORE"
"1","(975,3600)","0","pure_quanta_power","I14";
;
HDL_POWER"PVDDCR_CPU1_P1_PVCC"
CDS_LIB"pure_quanta_power";
"A"22;
%"UNIVERSAL_GND"
"1","(1325,2950)","0","pure_quanta_power","I15";
;
CDS_LIB"pure_quanta_power"
HDL_POWER"GND";
"A"3;
%"Q_CAP"
"1","(1325,3225)","0","pure_quanta","I16";
;
LOCATION"PC434_IOP1_2"
$SEC"1"
CDS_SEC"1"
PACK_TYPE"C0402"
VOLTAGE"10V"
VALUE"2.2UF"
TOLERANCE"10%"
MATERIAL"X6S"
CDS_LIB"pure_quanta"
PART_NUMBER"CH5222KEB01";
"B"
$PN"2"3;
"A"
$PN"1"22;
%"UNIVERSAL_GND"
"1","(3300,1525)","0","pure_quanta_power","I17";
;
CDS_LIB"pure_quanta_power"
HDL_POWER"GND";
"A"23;
%"UNIVERSAL_GND"
"1","(4025,1325)","0","pure_quanta_power","I18";
;
CDS_LIB"pure_quanta_power"
HDL_POWER"GND";
"A"4;
%"Q_RES"
"2","(4025,1550)","0","pure_quanta","I19";
;
LOCATION"PR489"
$SEC"1"
CDS_SEC"1"
PACK_TYPE"0402LF"
MATERIAL"EMPTY"
WATTAGE"1/8W"
VALUE"1.5"
TOLERANCE"1%"
CDS_LIB"pure_quanta"
PART_NUMBER"CS-1504FB00";
"A"
$PN"1"52;
"B"
$PN"2"4;
%"UNIVERSAL_GND"
"1","(100,4425)","0","pure_quanta_power","I2";
;
CDS_LIB"pure_quanta_power"
HDL_POWER"GND";
"A"5;
%"Q_CAP"
"1","(4025,2050)","0","pure_quanta","I20";
;
LOCATION"PC175"
$SEC"1"
CDS_SEC"1"
VOLTAGE"50V"
VALUE"560PF"
TOLERANCE"10%"
MATERIAL"EMPTY"
PACK_TYPE"C0402"
CDS_LIB"pure_quanta"
PART_NUMBER"CH1566K1B09";
"B"
$PN"2"52;
"A"
$PN"1"35;
%"Q_CAP"
"1","(3475,3175)","0","pure_quanta","I21";
;
LOCATION"PC439_2"
$SEC"1"
CDS_SEC"1"
VOLTAGE"25V"
VALUE"0.1UF"
TOLERANCE"10%"
MATERIAL"X7R"
PACK_TYPE"0402"
CDS_LIB"pure_quanta"
PART_NUMBER"CH4104K1B00";
"B"
$PN"2"17;
"A"
$PN"1"14;
%"Q_RES"
"1","(3925,2600)","0","pure_quanta","I22";
;
LOCATION"PR278"
$SEC"1"
CDS_SEC"1"
VALUE"5.6"
WATTAGE"1/16W"
MATERIAL"CHIP"
TOLERANCE"1%"
PACK_TYPE"0402LF"
CDS_LIB"pure_quanta"
PART_NUMBER"CS-5602FB01";
"B"
$PN"2"34;
"A"
$PN"1"13;
%"Q_CAP"
"1","(3975,3175)","0","pure_quanta","I23";
;
LOCATION"PC441_2"
$SEC"1"
CDS_SEC"1"
PACK_TYPE"C0402"
VOLTAGE"25V"
VALUE"1UF"
TOLERANCE"10%"
MATERIAL"X6S"
CDS_LIB"pure_quanta"
PART_NUMBER"CH5104KEB02";
"B"
$PN"2"17;
"A"
$PN"1"14;
%"UNIVERSAL_GND"
"1","(3300,4275)","0","pure_quanta_power","I24";
;
CDS_LIB"pure_quanta_power"
HDL_POWER"GND";
"A"24;
%"UNIVERSAL_GND"
"1","(4125,4075)","0","pure_quanta_power","I25";
;
CDS_LIB"pure_quanta_power"
HDL_POWER"GND";
"A"6;
%"Q_RES"
"2","(4125,4300)","0","pure_quanta","I26";
;
LOCATION"PR488"
$SEC"1"
CDS_SEC"1"
PACK_TYPE"0402LF"
MATERIAL"EMPTY"
WATTAGE"1/8W"
VALUE"1.5"
TOLERANCE"1%"
CDS_LIB"pure_quanta"
PART_NUMBER"CS-1504FB00";
"A"
$PN"1"40;
"B"
$PN"2"6;
%"UNIVERSAL_GND"
"1","(650,4325)","0","pure_quanta_power","I27";
;
CDS_LIB"pure_quanta_power"
HDL_POWER"GND";
"A"7;
%"Q_RES"
"2","(650,4550)","2","pure_quanta","I28";
;
LOCATION"PR275"
$SEC"1"
CDS_SEC"1"
VALUE"8.87K"
TOLERANCE"1%"
MATERIAL"EMPTY"
WATTAGE"1/16W"
PACK_TYPE"0402LF"
CDS_LIB"pure_quanta"
PART_NUMBER"CS28872FB01";
"A"
$PN"1"42;
"B"
$PN"2"7;
%"Q_CAP"
"1","(100,1875)","0","pure_quanta","I3";
;
LOCATION"PC436_8"
$SEC"1"
CDS_SEC"1"
VALUE"0.1UF"
PACK_TYPE"0402"
MATERIAL"X7R"
TOLERANCE"10%"
VOLTAGE"25V"
CDS_LIB"pure_quanta"
PART_NUMBER"CH4104K1B00";
"B"
$PN"2"1;
"A"
$PN"1"58;
%"UNIVERSAL_GND"
"1","(1075,5075)","0","pure_quanta_power","I33";
;
CDS_LIB"pure_quanta_power"
HDL_POWER"GND";
"A"8;
%"Q_CAP"
"1","(1075,5275)","0","pure_quanta","I34";
;
LOCATION"PC433"
$SEC"1"
CDS_SEC"1"
PACK_TYPE"C0402"
VOLTAGE"10V"
VALUE"2.2UF"
TOLERANCE"10%"
MATERIAL"X6S"
CDS_LIB"pure_quanta"
PART_NUMBER"CH5222KEB01";
"B"
$PN"2"8;
"A"
$PN"1"43;
%"Q_RES"
"2","(1075,5825)","0","pure_quanta","I35";
;
LOCATION"PR277"
$SEC"1"
CDS_SEC"1"
WATTAGE"1/16W"
MATERIAL"CHIP"
TOLERANCE"1%"
VALUE"2.2"
PACK_TYPE"0402LF"
CDS_LIB"pure_quanta"
PART_NUMBER"CS-2202FB01";
"A"
$PN"1"25;
"B"
$PN"2"43;
%"VCC_CORE"
"1","(1075,6225)","0","pure_quanta_power","I36";
;
HDL_POWER"PVDDCR_CPU1_P1_PVCC"
CDS_LIB"pure_quanta_power";
"A"25;
%"UNIVERSAL_GND"
"1","(1425,5575)","0","pure_quanta_power","I37";
;
CDS_LIB"pure_quanta_power"
HDL_POWER"GND";
"A"9;
%"Q_CAP"
"1","(1425,5850)","0","pure_quanta","I38";
;
LOCATION"PC437_IOP1_1"
$SEC"1"
CDS_SEC"1"
PACK_TYPE"C0402"
VOLTAGE"10V"
VALUE"2.2UF"
TOLERANCE"10%"
MATERIAL"X6S"
CDS_LIB"pure_quanta"
PART_NUMBER"CH5222KEB01";
"B"
$PN"2"9;
"A"
$PN"1"25;
%"ISL99390FRZTR5935"
"1","(2650,5000)","0","pure_quanta","I39";
;
LOCATION"PU39"
$SEC"1"
CDS_SEC"1"
VALUE"ISL99390FRZ-TR5935"
MATERIAL"IC"
PART_TYPE"SMLF"
CDS_LIB"pure_quanta"
CDS_LMAN_SYM_OUTLINE"-300,700,250,-650"
NEEDS_NO_SIZE"TRUE"
PART_NUMBER"AL099390004";
"PGND2"
$PN"7_9-20_24"24;
"GL2"
$PN"41"49;
"GL1"
$PN"6"41;
"DNC"
$PN"31"51;
"EN"
$PN"35"43;
"PGND3"
$PN"40"24;
"VOS"
$PN"1"18;
"VIN2"
$PN"30"16;
"PGND1"
$PN"5"24;
"SW"
$PN"10_19"19;
"LSET"
$PN"37"42;
"IOUT"
$PN"38"45;
"TOUT_FLT"
$PN"36"44;
"PVCC"
$PN"4"25;
"PHASE"
$PN"32"20;
"VIN1"
$PN"25_29"16;
"BOOT"
$PN"33"21;
"AGND"
$PN"2"24;
"VCC"
$PN"3"43;
"REFIN"
$PN"39"15;
"PWM"
$PN"34"50;
%"Q_CAP"
"1","(100,4625)","0","pure_quanta","I4";
;
LOCATION"PC435_7"
$SEC"1"
CDS_SEC"1"
PACK_TYPE"0402"
VOLTAGE"25V"
VALUE"0.1UF"
MATERIAL"X7R"
TOLERANCE"10%"
CDS_LIB"pure_quanta"
PART_NUMBER"CH4104K1B00";
"B"
$PN"2"5;
"A"
$PN"1"15;
%"Q_CAP"
"1","(4125,4800)","0","pure_quanta","I40";
;
LOCATION"PC174"
$SEC"1"
CDS_SEC"1"
PACK_TYPE"C0402"
TOLERANCE"10%"
VOLTAGE"50V"
VALUE"560PF"
MATERIAL"EMPTY"
CDS_LIB"pure_quanta"
PART_NUMBER"CH1566K1B09";
"B"
$PN"2"40;
"A"
$PN"1"19;
%"Q_CAP"
"1","(3325,5925)","0","pure_quanta","I41";
;
LOCATION"PC438_1"
$SEC"1"
CDS_SEC"1"
PACK_TYPE"0402"
VOLTAGE"25V"
VALUE"0.1UF"
MATERIAL"X7R"
TOLERANCE"10%"
CDS_LIB"pure_quanta"
PART_NUMBER"CH4104K1B00";
"B"
$PN"2"60;
"A"
$PN"1"16;
%"Q_CAP"
"1","(3675,5900)","0","pure_quanta","I42";
;
LOCATION"PC440_1"
$SEC"1"
CDS_SEC"1"
VALUE"1UF"
VOLTAGE"25V"
TOLERANCE"10%"
PACK_TYPE"C0402"
MATERIAL"X6S"
CDS_LIB"pure_quanta"
PART_NUMBER"CH5104KEB02";
"B"
$PN"2"60;
"A"
$PN"1"16;
%"Q_RES"
"1","(3975,5350)","0","pure_quanta","I43";
;
LOCATION"PR279"
$SEC"1"
CDS_SEC"1"
VALUE"5.6"
WATTAGE"1/16W"
MATERIAL"CHIP"
TOLERANCE"1%"
PACK_TYPE"0402LF"
CDS_LIB"pure_quanta"
PART_NUMBER"CS-5602FB01";
"B"
$PN"2"33;
"A"
$PN"1"21;
%"Q_CAP"
"1","(4000,5900)","0","pure_quanta","I44";
;
LOCATION"PC442_1"
$SEC"1"
CDS_SEC"1"
MATERIAL"X6S"
VOLTAGE"16V"
TOLERANCE"20%"
VALUE"22UF"
PACK_TYPE"C0805"
CDS_LIB"pure_quanta"
PART_NUMBER"CH6223MEA01";
"B"
$PN"2"60;
"A"
$PN"1"16;
%"Q_RES"
"1","(5000,1225)","0","pure_quanta","I45";
;
LOCATION"PR281"
$SEC"1"
CDS_SEC"1"
WATTAGE"1/16W"
MATERIAL"CHIP"
TOLERANCE"5%"
VALUE"0"
PACK_TYPE"0402LF"
CDS_LIB"pure_quanta"
PART_NUMBER"CS00002JB13";
"B"
$PN"2"27;
"A"
$PN"1"53;
%"Q_CAP"
"1","(4650,2475)","0","pure_quanta","I47";
;
LOCATION"PC445"
$SEC"1"
CDS_SEC"1"
PACK_TYPE"0402"
VOLTAGE"16V"
VALUE"0.22UF"
TOLERANCE"10%"
MATERIAL"X7R"
CDS_LIB"pure_quanta"
PART_NUMBER"CH4223K1B00";
"B"
$PN"2"36;
"A"
$PN"1"34;
%"Q_CAP"
"1","(4375,3175)","0","pure_quanta","I48";
;
LOCATION"PC443_2"
$SEC"1"
CDS_SEC"1"
MATERIAL"X6S"
VALUE"22UF"
VOLTAGE"16V"
TOLERANCE"20%"
PACK_TYPE"C0805"
CDS_LIB"pure_quanta"
PART_NUMBER"CH6223MEA01";
"B"
$PN"2"17;
"A"
$PN"1"14;
%"Q_CAP"
"1","(4775,3175)","0","pure_quanta","I49";
;
LOCATION"PC446_2"
$SEC"1"
CDS_SEC"1"
MATERIAL"X6S"
PACK_TYPE"C0805"
VALUE"22UF"
VOLTAGE"16V"
TOLERANCE"20%"
CDS_LIB"pure_quanta"
PART_NUMBER"CH6223MEA01";
"B"
$PN"2"17;
"A"
$PN"1"14;
%"UNIVERSAL_GND"
"1","(625,1525)","0","pure_quanta_power","I5";
;
CDS_LIB"pure_quanta_power"
HDL_POWER"GND";
"A"10;
%"Q_RES"
"1","(5175,4000)","0","pure_quanta","I50";
;
LOCATION"PR280"
$SEC"1"
CDS_SEC"1"
TOLERANCE"5%"
VALUE"0"
WATTAGE"1/16W"
MATERIAL"CHIP"
PACK_TYPE"0402LF"
CDS_LIB"pure_quanta"
PART_NUMBER"CS00002JB13";
"B"
$PN"2"32;
"A"
$PN"1"18;
%"UNIVERSAL_GND"
"1","(5250,2825)","0","pure_quanta_power","I51";
;
CDS_LIB"pure_quanta_power"
HDL_POWER"GND";
"A"17;
%"Q_CAP"
"1","(5250,3175)","0","pure_quanta","I52";
;
LOCATION"PC449_2"
$SEC"1"
CDS_SEC"1"
PACK_TYPE"C0805"
VALUE"22UF"
VOLTAGE"16V"
TOLERANCE"20%"
MATERIAL"X6S"
CDS_LIB"pure_quanta"
PART_NUMBER"CH6223MEA01";
"B"
$PN"2"17;
"A"
$PN"1"14;
%"VCC_CORE"
"1","(5250,3550)","0","pure_quanta_power","I53";
;
HDL_POWER"SW_P12V_AUX_PVDDIO_P1_FLT"
CDS_LIB"pure_quanta_power";
"A"14;
%"Q_CAP"
"1","(7475,2050)","0","pure_quanta","I55";
;
LOCATION"PC458_2"
$SEC"1"
CDS_SEC"1"
PACK_TYPE"C0805"
MATERIAL"X6S"
TOLERANCE"20%"
VALUE"22UF"
VOLTAGE"4V"
CDS_LIB"pure_quanta"
PART_NUMBER"CH622KMEA03";
"B"
$PN"2"26;
"A"
$PN"1"27;
%"UNIVERSAL_GND"
"1","(7900,1700)","0","pure_quanta_power","I56";
;
CDS_LIB"pure_quanta_power"
HDL_POWER"GND";
"A"26;
%"Q_CAP"
"1","(7900,2050)","0","pure_quanta","I57";
;
LOCATION"PC460_2"
$SEC"1"
CDS_SEC"1"
PACK_TYPE"C0805"
MATERIAL"X6S"
TOLERANCE"20%"
VALUE"22UF"
VOLTAGE"4V"
CDS_LIB"pure_quanta"
PART_NUMBER"CH622KMEA03";
"B"
$PN"2"26;
"A"
$PN"1"27;
%"Q_CAPP"
"1","(7000,3275)","0","pure_quanta","I58";
;
LOCATION"PC450"
$SEC"1"
CDS_SEC"1"
PACK_TYPE"SMLF"
VOLTAGE"2.5V"
VALUE"470UF"
TOLERANCE"20%"
MATERIAL"SPCAP"
CDS_LIB"pure_quanta"
PART_NUMBER"CH747LM8825";
"A"
$PN"1"29;
"B"
$PN"2"28;
%"Q_CAPP"
"1","(7400,3275)","0","pure_quanta","I59";
;
LOCATION"PC452"
$SEC"1"
CDS_SEC"1"
VOLTAGE"2.5V"
PACK_TYPE"SMLF"
VALUE"470UF"
TOLERANCE"20%"
MATERIAL"SPCAP"
CDS_LIB"pure_quanta"
PART_NUMBER"CH747LM8825";
"A"
$PN"1"29;
"B"
$PN"2"28;
%"Q_RES"
"2","(625,1750)","2","pure_quanta","I6";
;
LOCATION"PR274"
$SEC"1"
CDS_SEC"1"
PACK_TYPE"0402LF"
VALUE"8.87K"
TOLERANCE"1%"
MATERIAL"EMPTY"
WATTAGE"1/16W"
CDS_LIB"pure_quanta"
PART_NUMBER"CS28872FB01";
"A"
$PN"1"59;
"B"
$PN"2"10;
%"VCC_CORE"
"1","(7900,2400)","0","pure_quanta_power","I60";
;
HDL_POWER"PVDDIO_P1"
CDS_LIB"pure_quanta_power";
"A"27;
%"UNIVERSAL_GND"
"1","(7800,2925)","0","pure_quanta_power","I61";
;
CDS_LIB"pure_quanta_power"
HDL_POWER"GND";
"A"28;
%"Q_CAPP"
"1","(7800,3275)","0","pure_quanta","I62";
;
LOCATION"PC455"
$SEC"1"
CDS_SEC"1"
PACK_TYPE"SMLF"
VOLTAGE"2.5V"
VALUE"470UF"
TOLERANCE"20%"
MATERIAL"EMPTY"
CDS_LIB"pure_quanta"
PART_NUMBER"CH747LM8825";
"A"
$PN"1"29;
"B"
$PN"2"28;
%"VCC_CORE"
"1","(7800,3600)","0","pure_quanta_power","I63";
;
HDL_POWER"PVDDIO_P1"
CDS_LIB"pure_quanta_power";
"A"29;
%"Q_CAP"
"1","(5000,5225)","0","pure_quanta","I65";
;
LOCATION"PC447"
$SEC"1"
CDS_SEC"1"
PACK_TYPE"0402"
VOLTAGE"16V"
MATERIAL"X7R"
TOLERANCE"10%"
VALUE"0.22UF"
CDS_LIB"pure_quanta"
PART_NUMBER"CH4223K1B00";
"B"
$PN"2"20;
"A"
$PN"1"33;
%"Q_CAP"
"1","(4250,5900)","0","pure_quanta","I66";
;
LOCATION"PC444_1"
$SEC"1"
CDS_SEC"1"
MATERIAL"X6S"
VOLTAGE"16V"
VALUE"22UF"
TOLERANCE"20%"
PACK_TYPE"C0805"
CDS_LIB"pure_quanta"
PART_NUMBER"CH6223MEA01";
"B"
$PN"2"60;
"A"
$PN"1"16;
%"UNIVERSAL_GND"
"1","(4650,5525)","0","pure_quanta_power","I67";
;
CDS_LIB"pure_quanta_power"
HDL_POWER"GND";
"A"60;
%"VCC_CORE"
"1","(4650,6250)","0","pure_quanta_power","I68";
;
HDL_POWER"SW_P12V_AUX_PVDDIO_P1_FLT"
CDS_LIB"pure_quanta_power";
"A"16;
%"Q_CAP"
"1","(4775,5925)","0","pure_quanta","I69";
;
LOCATION"PC448_1"
$SEC"1"
CDS_SEC"1"
PACK_TYPE"C0805"
VALUE"22UF"
VOLTAGE"16V"
TOLERANCE"20%"
MATERIAL"X6S"
CDS_LIB"pure_quanta"
PART_NUMBER"CH6223MEA01";
"B"
$PN"2"60;
"A"
$PN"1"16;
%"Q_INDUCTOR4P_14"
"1","(5850,4875)","0","pure_quanta","I71";
;
LOCATION"PL47"
$SEC"1"
CDS_SEC"1"
VALUE"150NH"
PART_TYPE"SMLF"
MATERIAL"IND"
NEEDS_NO_SIZE"TRUE"
CDS_LIB"pure_quanta"
PART_NUMBER"CV+15^0TZ04";
"1"
$PN"1"19;
"4"
$PN"4"32;
"3"
$PN"3"30;
"2"
$PN"2"46;
%"Q_INDUCTOR"
"1","(5450,6175)","0","pure_quanta","I72";
;
LOCATION"PL49"
$SEC"1"
CDS_SEC"1"
PACK_TYPE"SMLF"
VALUE"50NH/86A"
MATERIAL"IND"
CDS_LIB"pure_quanta"
NEEDS_NO_SIZE"TRUE"
PART_NUMBER"CVA50^0MZ09";
"1"
$PN"1"16;
"2"
$PN"2"12;
%"UNIVERSAL_GND"
"1","(5850,5600)","0","pure_quanta_power","I73";
;
CDS_LIB"pure_quanta_power"
HDL_POWER"GND";
"A"11;
%"Q_CAP"
"1","(5850,5950)","0","pure_quanta","I74";
;
LOCATION"PC438"
$SEC"1"
CDS_SEC"1"
PACK_TYPE"0402"
MATERIAL"X7R"
VOLTAGE"25V"
VALUE"0.1UF"
TOLERANCE"10%"
CDS_LIB"pure_quanta"
PART_NUMBER"CH4104K1B00";
"B"
$PN"2"11;
"A"
$PN"1"12;
%"VCC_CORE"
"1","(5850,6275)","0","pure_quanta_power","I75";
;
HDL_POWER"P12V_AUX"
CDS_LIB"pure_quanta_power";
"A"12;
%"UNIVERSAL_GND"
"1","(6775,4625)","0","pure_quanta_power","I76";
;
CDS_LIB"pure_quanta_power"
HDL_POWER"GND";
"A"30;
%"Q_CAP"
"1","(7175,4800)","0","pure_quanta","I77";
;
LOCATION"PC451"
$SEC"1"
CDS_SEC"1"
PACK_TYPE"C0402"
VOLTAGE"50V"
VALUE"100NF"
TOLERANCE"10%"
MATERIAL"X7R"
CDS_LIB"pure_quanta"
PART_NUMBER"CH4106K1B01";
"B"
$PN"2"31;
"A"
$PN"1"32;
%"Q_CAP"
"1","(7500,4800)","0","pure_quanta","I78";
;
LOCATION"PC456_1"
$SEC"1"
CDS_SEC"1"
PACK_TYPE"C0805"
VOLTAGE"4V"
VALUE"22UF"
TOLERANCE"20%"
MATERIAL"X6S"
CDS_LIB"pure_quanta"
PART_NUMBER"CH622KMEA03";
"B"
$PN"2"31;
"A"
$PN"1"32;
%"Q_CAP"
"1","(7950,4800)","0","pure_quanta","I79";
;
LOCATION"PC459_1"
$SEC"1"
CDS_SEC"1"
PACK_TYPE"C0805"
MATERIAL"X6S"
TOLERANCE"20%"
VALUE"22UF"
VOLTAGE"4V"
CDS_LIB"pure_quanta"
PART_NUMBER"CH622KMEA03";
"B"
$PN"2"31;
"A"
$PN"1"32;
%"UNIVERSAL_GND"
"1","(8250,4450)","0","pure_quanta_power","I80";
;
CDS_LIB"pure_quanta_power"
HDL_POWER"GND";
"A"31;
%"Q_RES"
"2","(8250,4800)","0","pure_quanta","I81";
;
LOCATION"PR378"
$SEC"1"
CDS_SEC"1"
WATTAGE"1/16W"
MATERIAL"CHIP"
TOLERANCE"1%"
VALUE"1K"
PACK_TYPE"0402LF"
CDS_LIB"pure_quanta"
PART_NUMBER"CS21002FB06";
"A"
$PN"1"32;
"B"
$PN"2"31;
%"VCC_CORE"
"1","(8250,5100)","0","pure_quanta_power","I82";
;
HDL_POWER"PVDDIO_P1"
CDS_LIB"pure_quanta_power";
"A"32;
%"Q_INDUCTOR4P_14"
"1","(6025,2125)","0","pure_quanta","I83";
;
LOCATION"PL48"
$SEC"1"
CDS_SEC"1"
VALUE"150NH"
MATERIAL"IND"
PART_TYPE"SMLF"
NEEDS_NO_SIZE"TRUE"
CDS_LIB"pure_quanta"
PART_NUMBER"CV+15^0TZ04";
"1"
$PN"1"35;
"4"
$PN"4"27;
"3"
$PN"3"47;
"2"
$PN"2"48;
%"ISL99390FRZTR5935"
"1","(2650,2250)","0","pure_quanta","I84";
;
LOCATION"PU40"
$SEC"1"
CDS_SEC"1"
VALUE"ISL99390FRZ-TR5935"
MATERIAL"IC"
PART_TYPE"SMLF"
NEEDS_NO_SIZE"TRUE"
CDS_LMAN_SYM_OUTLINE"-300,700,250,-650"
CDS_LIB"pure_quanta"
PART_NUMBER"AL099390004";
"PGND2"
$PN"7_9-20_24"23;
"GL2"
$PN"41"55;
"GL1"
$PN"6"54;
"DNC"
$PN"31"57;
"EN"
$PN"35"39;
"PGND3"
$PN"40"23;
"VOS"
$PN"1"53;
"VIN2"
$PN"30"14;
"PGND1"
$PN"5"23;
"SW"
$PN"10_19"35;
"LSET"
$PN"37"59;
"IOUT"
$PN"38"56;
"TOUT_FLT"
$PN"36"37;
"PVCC"
$PN"4"22;
"PHASE"
$PN"32"36;
"VIN1"
$PN"25_29"14;
"BOOT"
$PN"33"13;
"AGND"
$PN"2"23;
"VCC"
$PN"3"39;
"REFIN"
$PN"39"58;
"PWM"
$PN"34"38;
%"Q_CAPP"
"1","(5075,5925)","0","pure_quanta","I85";
;
LOCATION"PC454"
$SEC"1"
CDS_SEC"1"
MATERIAL"OSCON"
PACK_TYPE"SMLF"
VOLTAGE"16V"
VALUE"270UF"
TOLERANCE"20%"
CDS_LIB"pure_quanta"
PART_NUMBER"CC72703MZ11";
"A"
$PN"1"16;
"B"
$PN"2"60;
%"Q_CAP"
"1","(4500,5925)","0","pure_quanta","I86";
;
LOCATION"PC7001"
$SEC"1"
CDS_SEC"1"
PACK_TYPE"C0805"
VALUE"22UF"
VOLTAGE"16V"
TOLERANCE"20%"
MATERIAL"X6S"
CDS_LIB"pure_quanta"
PART_NUMBER"CH6223MEA01";
"B"
$PN"2"60;
"A"
$PN"1"16;
END.
